#ISCELL
  pure_quanta quanta_title_block_c *
  *
#ISCELL
  logical_power universal_gnd *
  page241_i10
#CELL
  pure_quanta q_led *
  page241_i11
#ISCELL
  logical_power universal_power *
  page241_i15
#CELL
  pure_quanta mosfet_nch_dual *
  page241_i16
#CELL
  pure_quanta mosfet_nch_dual *
  page241_i17
#ISCELL
  logical_power universal_gnd *
  page241_i18
#CELL
  pure_quanta q_led *
  page241_i19
#CELL
  pure_quanta q_led *
  page241_i20
#ISCELL
  logical_power universal_power *
  page241_i24
#ISCELL
  logical_power universal_power *
  page241_i25
#ISCELL
  standard offpage *
  page241_i26
#ISCELL
  standard offpage *
  page241_i3
#ISCELL
  logical_power universal_gnd *
  page241_i31
#CELL
  pure_quanta q_led *
  page241_i33
#ISCELL
  logical_power universal_power *
  page241_i37
#CELL
  pure_quanta q_res *
  page241_i38
#CELL
  pure_quanta q_res *
  page241_i39
#ISCELL
  standard offpage *
  page241_i4
#CELL
  pure_quanta q_res *
  page241_i40
#CELL
  pure_quanta q_res *
  page241_i41
#CELL
  pure_quanta mosfet_nch_dual *
  page241_i42
#ISCELL
  logical_power universal_power *
  page241_i47
#CELL
  pure_quanta q_led *
  page241_i49
#ISCELL
  standard offpage *
  page241_i5
#ISCELL
  logical_power universal_gnd *
  page241_i50
#ISCELL
  logical_power universal_power *
  page241_i54
#CELL
  pure_quanta q_led *
  page241_i58
#ISCELL
  logical_power universal_gnd *
  page241_i59
#CELL
  pure_quanta q_res *
  page241_i61
#CELL
  pure_quanta q_res *
  page241_i62
#CELL
  pure_quanta q_res *
  page241_i63
#CELL
  pure_quanta q_res *
  page241_i64
#CELL
  pure_quanta q_res *
  page241_i65
#CELL
  pure_quanta q_res *
  page241_i66
#CELL
  pure_quanta q_led *
  page241_i67
#CELL
  pure_quanta q_res *
  page241_i68
#CELL
  pure_quanta mosfet_nch_dual *
  page241_i69
#ISCELL
  logical_power universal_power *
  page241_i71
#CELL
  pure_quanta mosfet_nch_dual *
  page241_i72
#ISCELL
  logical_power universal_gnd *
  page241_i73
#CELL
  pure_quanta q_res *
  page241_i74
#ISCELL
  logical_power universal_power *
  page241_i75
#ISCELL
  logical_power universal_gnd *
  page241_i76
#ISCELL
  standard offpage *
  page241_i77
#CELL
  pure_quanta mosfet_nch_dual *
  page241_i8
#ISCELL
  logical_power universal_gnd *
  page241_i9
